(kicad_pcb
	(version 20241229)
	(generator "pcbnew")
	(generator_version "9.0")
	(general
		(thickness 1.294)
		(legacy_teardrops no)
	)
	(paper "A3")
	(title_block
		(title "Kintex 410T devboard")
		(date "2024-04-03")
		(rev "1.1.2")
		(comment 9 "footprints 56-60 of 975")
	)
	(layers
		(0 "F.Cu" mixed)
		(4 "In1.Cu" power)
		(6 "In2.Cu" power)
		(8 "In3.Cu" mixed)
		(10 "In4.Cu" power)
		(12 "In5.Cu" mixed)
		(14 "In6.Cu" power)
		(16 "In7.Cu" mixed)
		(18 "In8.Cu" power)
		(2 "B.Cu" mixed)
		(9 "F.Adhes" user "F.Adhesive")
		(11 "B.Adhes" user "B.Adhesive")
		(13 "F.Paste" user)
		(15 "B.Paste" user)
		(5 "F.SilkS" user "F.Silkscreen")
		(7 "B.SilkS" user "B.Silkscreen")
		(1 "F.Mask" user)
		(3 "B.Mask" user)
		(17 "Dwgs.User" user "User.Drawings")
		(19 "Cmts.User" user "User.Comments")
		(21 "Eco1.User" user "User.Eco1")
		(23 "Eco2.User" user "User.Eco2")
		(25 "Edge.Cuts" user)
		(27 "Margin" user)
		(31 "F.CrtYd" user "F.Courtyard")
		(29 "B.CrtYd" user "B.Courtyard")
		(35 "F.Fab" user)
		(33 "B.Fab" user)
	)
	(footprint "antmicro-footprints:C_0402_1005Metric"
		(layer "F.Cu")
		(at 247.099 118.904 180)
		(descr "Capacitor SMD 0402")
		(tags "capacitor SMD 0402")
		(property "Reference" "C396"
			(at 0.999 -1.196 180)
			(layer "F.SilkS")
			(effects
				(font
					(size 0.7 0.7)
					(thickness 0.15)
				)
				(justify left bottom)
			)
		)
		(property "Value" "C_100n_0402"
			(at 0 1.169 180)
			(layer "F.Fab")
			(effects
				(font
					(size 0.7 0.7)
					(thickness 0.15)
				)
				(justify left bottom)
			)
		)
		(property "Description" "SMD Multilayer Ceramic Capacitor, 0.1 µF, 50 V, 0402 [1005 Metric], ± 10%, X5R, GRM Series"
			(at 0 0 180)
			(layer "F.Fab")
			(hide yes)
			(effects
				(font
					(size 1.27 1.27)
					(thickness 0.15)
				)
			)
		)
		(property "Author" "Antmicro"
			(at 494.198 237.808 0)
			(layer "F.Fab")
			(hide yes)
			(effects
				(font
					(size 1 1)
					(thickness 0.15)
				)
			)
		)
		(property "Dielectric" "X5R"
			(at 494.198 237.808 0)
			(layer "F.Fab")
			(hide yes)
			(effects
				(font
					(size 1 1)
					(thickness 0.15)
				)
			)
		)
		(property "License" "Apache-2.0"
			(at 494.198 237.808 0)
			(layer "F.Fab")
			(hide yes)
			(effects
				(font
					(size 1 1)
					(thickness 0.15)
				)
			)
		)
		(property "MPN" "GRM155R61H104KE14D"
			(at 494.198 237.808 0)
			(layer "F.Fab")
			(hide yes)
			(effects
				(font
					(size 1 1)
					(thickness 0.15)
				)
			)
		)
		(property "Manufacturer" "Murata"
			(at 494.198 237.808 0)
			(layer "F.Fab")
			(hide yes)
			(effects
				(font
					(size 1 1)
					(thickness 0.15)
				)
			)
		)
		(property "Val" "100n"
			(at 494.198 237.808 0)
			(layer "F.Fab")
			(hide yes)
			(effects
				(font
					(size 1 1)
					(thickness 0.15)
				)
			)
		)
		(property "Voltage" "50V"
			(at 494.198 237.808 0)
			(layer "F.Fab")
			(hide yes)
			(effects
				(font
					(size 1 1)
					(thickness 0.15)
				)
			)
		)
		(sheetname "USB PHY")
		(sheetfile "usb-phy.kicad_sch")
		(attr smd)
		(fp_rect
			(start -0.925 -0.47)
			(end 0.925 0.47)
			(stroke
				(width 0.05)
				(type default)
			)
			(fill no)
			(layer "F.CrtYd")
		)
		(fp_line
			(start 0.504 0.248)
			(end -0.494 0.248)
			(stroke
				(width 0.15)
				(type solid)
			)
			(layer "F.Fab")
		)
		(fp_line
			(start 0.504 -0.25)
			(end 0.504 0.248)
			(stroke
				(width 0.15)
				(type solid)
			)
			(layer "F.Fab")
		)
		(fp_line
			(start -0.494 0.248)
			(end -0.494 -0.25)
			(stroke
				(width 0.15)
				(type solid)
			)
			(layer "F.Fab")
		)
		(fp_line
			(start -0.494 -0.25)
			(end 0.504 -0.25)
			(stroke
				(width 0.15)
				(type solid)
			)
			(layer "F.Fab")
		)
		(pad "1" smd roundrect
			(at -0.48 0 180)
			(size 0.59 0.64)
			(layers "F.Cu" "F.Mask" "F.Paste")
			(roundrect_rratio 0.25)
			(net 1 "GND")
			(pintype "passive")
		)
		(pad "2" smd roundrect
			(at 0.48 0 180)
			(size 0.59 0.64)
			(layers "F.Cu" "F.Mask" "F.Paste")
			(roundrect_rratio 0.25)
			(net 715 "/USB PHY/USB_USR_VBUS")
			(pintype "passive")
		)
	)
	(footprint "antmicro-footprints:WDFN-8-1EP_6x5mm_P1.27mm_EP3.4x4mm"
		(layer "F.Cu")
		(at 230.425 119.925)
		(property "Reference" "U12"
			(at -3.7 -3.2 0)
			(layer "F.SilkS")
			(effects
				(font
					(size 0.7 0.7)
					(thickness 0.15)
				)
				(justify left bottom)
			)
		)
		(property "Value" "MT25QL256ABA1EW7-0SIT"
			(at -10.1 4 0)
			(layer "F.Fab")
			(effects
				(font
					(size 0.7 0.7)
					(thickness 0.15)
				)
				(justify left bottom)
			)
		)
		(property "Description" "Flash Memory, Serial NOR, 256 Mbit, 32M x 8bit, SPI, MLP, 8 Pins"
			(at 0 0 0)
			(layer "F.Fab")
			(hide yes)
			(effects
				(font
					(size 1.27 1.27)
					(thickness 0.15)
				)
			)
		)
		(property "Author" "Antmicro"
			(at 0 0 0)
			(layer "F.Fab")
			(hide yes)
			(effects
				(font
					(size 1 1)
					(thickness 0.15)
				)
			)
		)
		(property "License" "Apache-2.0"
			(at 0 0 0)
			(layer "F.Fab")
			(hide yes)
			(effects
				(font
					(size 1 1)
					(thickness 0.15)
				)
			)
		)
		(property "MPN" "MT25QL256ABA1EW7-0SIT"
			(at 0 0 0)
			(layer "F.Fab")
			(hide yes)
			(effects
				(font
					(size 1 1)
					(thickness 0.15)
				)
			)
		)
		(property "Manufacturer" "Micron Technology"
			(at 0 0 0)
			(layer "F.Fab")
			(hide yes)
			(effects
				(font
					(size 1 1)
					(thickness 0.15)
				)
			)
		)
		(sheetname "SPI Flash + SD Card")
		(sheetfile "spi-flash.kicad_sch")
		(attr smd)
		(fp_line
			(start -3.801 2.6)
			(end 3.7 2.6)
			(stroke
				(width 0.15)
				(type solid)
			)
			(layer "F.SilkS")
		)
		(fp_line
			(start -2.301 -2.601)
			(end 3.7 -2.601)
			(stroke
				(width 0.15)
				(type solid)
			)
			(layer "F.SilkS")
		)
		(fp_circle
			(center -3.3 -2.8)
			(end -3.25 -2.8)
			(stroke
				(width 0.15)
				(type solid)
			)
			(fill yes)
			(layer "F.SilkS")
		)
		(fp_rect
			(start -3.5 -3)
			(end 3.499 2.999)
			(stroke
				(width 0.05)
				(type solid)
			)
			(fill no)
			(layer "F.CrtYd")
		)
		(fp_line
			(start -3 -1.5)
			(end -3 2.499)
			(stroke
				(width 0.15)
				(type solid)
			)
			(layer "F.Fab")
		)
		(fp_line
			(start -3 2.499)
			(end 2.999 2.499)
			(stroke
				(width 0.15)
				(type solid)
			)
			(layer "F.Fab")
		)
		(fp_line
			(start -2 -2.5)
			(end -3 -1.5)
			(stroke
				(width 0.15)
				(type solid)
			)
			(layer "F.Fab")
		)
		(fp_line
			(start 2.999 -2.5)
			(end -2 -2.5)
			(stroke
				(width 0.15)
				(type solid)
			)
			(layer "F.Fab")
		)
		(fp_line
			(start 2.999 2.499)
			(end 2.999 -2.5)
			(stroke
				(width 0.15)
				(type solid)
			)
			(layer "F.Fab")
		)
		(pad "" smd roundrect
			(at -0.802 -1)
			(size 1.37 1.61)
			(layers "F.Paste")
			(roundrect_rratio 0.182482)
		)
		(pad "" smd roundrect
			(at -0.802 0.998)
			(size 1.37 1.61)
			(layers "F.Paste")
			(roundrect_rratio 0.182482)
		)
		(pad "" smd roundrect
			(at 0.8 -1)
			(size 1.37 1.61)
			(layers "F.Paste")
			(roundrect_rratio 0.182482)
		)
		(pad "" smd roundrect
			(at 0.8 0.998)
			(size 1.37 1.61)
			(layers "F.Paste")
			(roundrect_rratio 0.182482)
		)
		(pad "1" smd rect
			(at -3 -1.905 90)
			(size 0.5 1.5)
			(layers "F.Cu" "F.Mask" "F.Paste")
			(net 894 "/SPI Flash + SD Card/SYSTEM_FLASH_~{CS}")
			(pinfunction "~{CS}")
			(pintype "passive")
		)
		(pad "2" smd roundrect
			(at -3 -0.635 90)
			(size 0.5 1.5)
			(layers "F.Cu" "F.Mask" "F.Paste")
			(roundrect_rratio 0.25)
			(net 897 "/SPI Flash + SD Card/SYSTEM_FLASH_DQ1")
			(pinfunction "DQ1")
			(pintype "passive")
		)
		(pad "3" smd roundrect
			(at -3 0.633 90)
			(size 0.5 1.5)
			(layers "F.Cu" "F.Mask" "F.Paste")
			(roundrect_rratio 0.25)
			(net 898 "/SPI Flash + SD Card/SYSTEM_FLASH_DQ2")
			(pinfunction "DQ2/~{W}")
			(pintype "passive")
		)
		(pad "4" smd roundrect
			(at -3 1.904 90)
			(size 0.5 1.5)
			(layers "F.Cu" "F.Mask" "F.Paste")
			(roundrect_rratio 0.25)
			(net 1 "GND")
			(pinfunction "GND")
			(pintype "passive")
		)
		(pad "5" smd roundrect
			(at 2.999 1.904 90)
			(size 0.5 1.5)
			(layers "F.Cu" "F.Mask" "F.Paste")
			(roundrect_rratio 0.25)
			(net 896 "/SPI Flash + SD Card/SYSTEM_FLASH_DQ0")
			(pinfunction "DQ0")
			(pintype "passive")
		)
		(pad "6" smd roundrect
			(at 2.999 0.633 90)
			(size 0.5 1.5)
			(layers "F.Cu" "F.Mask" "F.Paste")
			(roundrect_rratio 0.25)
			(net 895 "/SPI Flash + SD Card/SYSTEM_FLASH_CLK")
			(pinfunction "CLK")
			(pintype "passive")
		)
		(pad "7" smd roundrect
			(at 2.999 -0.635 90)
			(size 0.5 1.5)
			(layers "F.Cu" "F.Mask" "F.Paste")
			(roundrect_rratio 0.25)
			(net 899 "/SPI Flash + SD Card/SYSTEM_FLASH_DQ3")
			(pinfunction "DQ3/~{HOLD}")
			(pintype "passive")
		)
		(pad "8" smd roundrect
			(at 2.999 -1.905 90)
			(size 0.5 1.5)
			(layers "F.Cu" "F.Mask" "F.Paste")
			(roundrect_rratio 0.25)
			(net 24 "+3V3")
			(pinfunction "VCC")
			(pintype "passive")
		)
		(pad "9" smd rect
			(at 0 0)
			(size 3.4 4)
			(layers "F.Cu" "F.Mask")
			(net 1 "GND")
			(pinfunction "EP")
			(pintype "passive")
			(solder_paste_margin -0.1)
		)
	)
	(footprint "antmicro-footprints:R_0603_1608Metric"
		(layer "F.Cu")
		(at 169.1 172.8 90)
		(descr "Resistor SMD 0603")
		(tags "resistor SMD 0603")
		(property "Reference" "R292"
			(at 3.7 -2.35 90)
			(layer "F.SilkS")
			(effects
				(font
					(size 0.7 0.7)
					(thickness 0.15)
				)
				(justify left bottom)
			)
		)
		(property "Value" "R_0R_22.4A_0603"
			(at 0 1.6 90)
			(layer "F.Fab")
			(effects
				(font
					(size 0.7 0.7)
					(thickness 0.15)
				)
				(justify left bottom)
			)
		)
		(property "Description" "SMD Chip Resistor"
			(at 0 0 90)
			(layer "F.Fab")
			(hide yes)
			(effects
				(font
					(size 1.27 1.27)
					(thickness 0.15)
				)
			)
		)
		(property "Author" "Antmicro"
			(at 341.9 3.7 0)
			(layer "F.Fab")
			(hide yes)
			(effects
				(font
					(size 1 1)
					(thickness 0.15)
				)
			)
		)
		(property "License" "Apache-2.0"
			(at 341.9 3.7 0)
			(layer "F.Fab")
			(hide yes)
			(effects
				(font
					(size 1 1)
					(thickness 0.15)
				)
			)
		)
		(property "MPN" "PMR03EZPJ000"
			(at 341.9 3.7 0)
			(layer "F.Fab")
			(hide yes)
			(effects
				(font
					(size 1 1)
					(thickness 0.15)
				)
			)
		)
		(property "Manufacturer" "ROHM Semiconductor"
			(at 341.9 3.7 0)
			(layer "F.Fab")
			(hide yes)
			(effects
				(font
					(size 1 1)
					(thickness 0.15)
				)
			)
		)
		(property "Max. Curr." "22.4A"
			(at 341.9 3.7 0)
			(layer "F.Fab")
			(hide yes)
			(effects
				(font
					(size 1 1)
					(thickness 0.15)
				)
			)
		)
		(property "Tolerance" "template_tolerance"
			(at 341.9 3.7 0)
			(layer "F.Fab")
			(hide yes)
			(effects
				(font
					(size 1 1)
					(thickness 0.15)
				)
			)
		)
		(property "Val" "0R"
			(at 341.9 3.7 0)
			(layer "F.Fab")
			(hide yes)
			(effects
				(font
					(size 1 1)
					(thickness 0.15)
				)
			)
		)
		(sheetname "DC-DC Converters")
		(sheetfile "dc-dc.kicad_sch")
		(attr smd)
		(fp_line
			(start -0.15 -0.4)
			(end 0.15 -0.4)
			(stroke
				(width 0.15)
				(type solid)
			)
			(layer "F.SilkS")
		)
		(fp_line
			(start -0.15 0.4)
			(end 0.15 0.4)
			(stroke
				(width 0.15)
				(type solid)
			)
			(layer "F.SilkS")
		)
		(fp_rect
			(start -1.25 -0.65)
			(end 1.25 0.65)
			(stroke
				(width 0.05)
				(type solid)
			)
			(fill no)
			(layer "F.CrtYd")
		)
		(fp_rect
			(start -0.8 -0.4)
			(end 0.8 0.4)
			(stroke
				(width 0.15)
				(type solid)
			)
			(fill no)
			(layer "F.Fab")
		)
		(pad "1" smd roundrect
			(at -0.7 0 90)
			(size 0.8 1)
			(layers "F.Cu" "F.Mask" "F.Paste")
			(roundrect_rratio 0.2)
			(net 740 "/DC-DC Converters/1V35_local")
			(pintype "passive")
		)
		(pad "2" smd roundrect
			(at 0.7 0 90)
			(size 0.8 1)
			(layers "F.Cu" "F.Mask" "F.Paste")
			(roundrect_rratio 0.2)
			(net 25 "+1V35")
			(pintype "passive")
		)
	)
	(footprint "antmicro-footprints:C_0402_1005Metric"
		(layer "F.Cu")
		(at 202.6625 88.3365 -90)
		(descr "Capacitor SMD 0402")
		(tags "capacitor SMD 0402")
		(property "Reference" "C261"
			(at -0.8865 -0.3875 270)
			(layer "F.SilkS")
			(effects
				(font
					(size 0.7 0.7)
					(thickness 0.15)
				)
				(justify left bottom)
			)
		)
		(property "Value" "C_100n_0402"
			(at 0 1.169 270)
			(layer "F.Fab")
			(effects
				(font
					(size 0.7 0.7)
					(thickness 0.15)
				)
				(justify left bottom)
			)
		)
		(property "Description" "SMD Multilayer Ceramic Capacitor, 0.1 µF, 50 V, 0402 [1005 Metric], ± 10%, X5R, GRM Series"
			(at 0 0 270)
			(layer "F.Fab")
			(hide yes)
			(effects
				(font
					(size 1.27 1.27)
					(thickness 0.15)
				)
			)
		)
		(property "Author" "Antmicro"
			(at 114.326 290.999 0)
			(layer "F.Fab")
			(hide yes)
			(effects
				(font
					(size 1 1)
					(thickness 0.15)
				)
			)
		)
		(property "Dielectric" "X5R"
			(at 114.326 290.999 0)
			(layer "F.Fab")
			(hide yes)
			(effects
				(font
					(size 1 1)
					(thickness 0.15)
				)
			)
		)
		(property "License" "Apache-2.0"
			(at 114.326 290.999 0)
			(layer "F.Fab")
			(hide yes)
			(effects
				(font
					(size 1 1)
					(thickness 0.15)
				)
			)
		)
		(property "MPN" "GRM155R61H104KE14D"
			(at 114.326 290.999 0)
			(layer "F.Fab")
			(hide yes)
			(effects
				(font
					(size 1 1)
					(thickness 0.15)
				)
			)
		)
		(property "Manufacturer" "Murata"
			(at 114.326 290.999 0)
			(layer "F.Fab")
			(hide yes)
			(effects
				(font
					(size 1 1)
					(thickness 0.15)
				)
			)
		)
		(property "Val" "100n"
			(at 114.326 290.999 0)
			(layer "F.Fab")
			(hide yes)
			(effects
				(font
					(size 1 1)
					(thickness 0.15)
				)
			)
		)
		(property "Voltage" "50V"
			(at 114.326 290.999 0)
			(layer "F.Fab")
			(hide yes)
			(effects
				(font
					(size 1 1)
					(thickness 0.15)
				)
			)
		)
		(sheetname "HDMI + Ethernet")
		(sheetfile "hdmi-ethernet.kicad_sch")
		(attr smd)
		(fp_rect
			(start -0.925 -0.47)
			(end 0.925 0.47)
			(stroke
				(width 0.05)
				(type default)
			)
			(fill no)
			(layer "F.CrtYd")
		)
		(fp_line
			(start -0.494 0.248)
			(end -0.494 -0.25)
			(stroke
				(width 0.15)
				(type solid)
			)
			(layer "F.Fab")
		)
		(fp_line
			(start 0.504 0.248)
			(end -0.494 0.248)
			(stroke
				(width 0.15)
				(type solid)
			)
			(layer "F.Fab")
		)
		(fp_line
			(start -0.494 -0.25)
			(end 0.504 -0.25)
			(stroke
				(width 0.15)
				(type solid)
			)
			(layer "F.Fab")
		)
		(fp_line
			(start 0.504 -0.25)
			(end 0.504 0.248)
			(stroke
				(width 0.15)
				(type solid)
			)
			(layer "F.Fab")
		)
		(pad "1" smd roundrect
			(at -0.48 0 270)
			(size 0.59 0.64)
			(layers "F.Cu" "F.Mask" "F.Paste")
			(roundrect_rratio 0.25)
			(net 1 "GND")
			(pintype "passive")
		)
		(pad "2" smd roundrect
			(at 0.48 0 270)
			(size 0.59 0.64)
			(layers "F.Cu" "F.Mask" "F.Paste")
			(roundrect_rratio 0.25)
			(net 24 "+3V3")
			(pintype "passive")
		)
	)
	(footprint "antmicro-footprints:Heatsink_960-31-18-S-AB-0"
		(layer "F.Cu")
		(at 200.000001 130.000001 90)
		(property "Reference" "HS1"
			(at -16.649999 13.449999 180)
			(unlocked yes)
			(layer "F.SilkS")
			(effects
				(font
					(size 0.7 0.7)
					(thickness 0.15)
				)
				(justify left bottom)
			)
		)
		(property "Value" "Heatsink_960-31-18-S-AB-0"
			(at -7.7 0.94 90)
			(unlocked yes)
			(layer "F.Fab")
			(effects
				(font
					(size 0.7 0.7)
					(thickness 0.15)
				)
				(justify left bottom)
			)
		)
		(property "Description" "Heat Sink BGA Aluminum Top Mount"
			(at 0 0 90)
			(layer "F.Fab")
			(hide yes)
			(effects
				(font
					(size 1.27 1.27)
					(thickness 0.15)
				)
			)
		)
		(property "Author" "Antmicro"
			(at 330.000002 -70 0)
			(layer "F.Fab")
			(hide yes)
			(effects
				(font
					(size 1 1)
					(thickness 0.15)
				)
			)
		)
		(property "DNP" "DNP"
			(at 330.000002 -70 0)
			(layer "F.Fab")
			(hide yes)
			(effects
				(font
					(size 1 1)
					(thickness 0.15)
				)
			)
		)
		(property "License" "Apache-2.0"
			(at 330.000002 -70 0)
			(layer "F.Fab")
			(hide yes)
			(effects
				(font
					(size 1 1)
					(thickness 0.15)
				)
			)
		)
		(property "MPN" "960-31-18-S-AB-0"
			(at 330.000002 -70 0)
			(layer "F.Fab")
			(hide yes)
			(effects
				(font
					(size 1 1)
					(thickness 0.15)
				)
			)
		)
		(property "Manufacturer" "Wakefield-Vette"
			(at 330.000002 -70 0)
			(layer "F.Fab")
			(hide yes)
			(effects
				(font
					(size 1 1)
					(thickness 0.15)
				)
			)
		)
		(property "dnp" ""
			(at 330.000002 -70 0)
			(layer "F.Fab")
			(hide yes)
			(effects
				(font
					(size 1 1)
					(thickness 0.15)
				)
			)
		)
		(property "exclude_from_bom" ""
			(at 330.000002 -70 0)
			(layer "F.Fab")
			(hide yes)
			(effects
				(font
					(size 1 1)
					(thickness 0.15)
				)
			)
		)
		(sheetfile "k410t-devboard.kicad_sch")
		(attr exclude_from_pos_files exclude_from_bom)
		(fp_circle
			(center 19.17 -12.33)
			(end 21.72 -12.33)
			(stroke
				(width 0.05)
				(type solid)
			)
			(fill no)
			(layer "F.CrtYd")
		)
		(fp_circle
			(center -19.18 12.32)
			(end -16.64 12.32)
			(stroke
				(width 0.05)
				(type solid)
			)
			(fill no)
			(layer "F.CrtYd")
		)
		(fp_rect
			(start -22.6 -15.75)
			(end 22.6 15.75)
			(stroke
				(width 0.15)
				(type solid)
			)
			(fill no)
			(layer "F.Fab")
		)
		(pad "" np_thru_hole circle
			(at -19.176 12.32 90)
			(size 3.18 3.18)
			(drill 3.18)
			(layers "F&B.Cu" "*.Mask")
		)
		(pad "" np_thru_hole circle
			(at 19.184 -12.321 90)
			(size 3.18 3.18)
			(drill 3.18)
			(layers "F&B.Cu" "*.Mask")
		)
	)
)
